(kicad_pcb
	(version 20260206)
	(generator "pcbnew")
	(generator_version "10.0")
	(general
		(thickness 1.6)
		(legacy_teardrops no)
	)
	(paper "A4")
	(title_block
		(title "04192023_DAF0TMB3IC0_F0TG_MB_C_brd_V02_OCP.brd")
		(comment 1 "Grand Teton / footprints 3365-3372 of 8354")
	)
	(layers
		(0 "F.Cu" signal "TOP")
		(4 "In1.Cu" signal "GND")
		(6 "In2.Cu" signal "IN1")
		(8 "In3.Cu" signal "GND1")
		(10 "In4.Cu" signal "IN2")
		(12 "In5.Cu" signal "GND2")
		(14 "In6.Cu" signal "IN3")
		(16 "In7.Cu" signal "GND3")
		(18 "In8.Cu" signal "VCC")
		(20 "In9.Cu" signal "VCC1")
		(22 "In10.Cu" signal "GND4")
		(24 "In11.Cu" signal "IN4")
		(26 "In12.Cu" signal "GND5")
		(28 "In13.Cu" signal "IN5")
		(30 "In14.Cu" signal "GND6")
		(32 "In15.Cu" signal "IN6")
		(34 "In16.Cu" signal "GND7")
		(2 "B.Cu" signal "BOTTOM")
		(9 "F.Adhes" user "F.Adhesive")
		(11 "B.Adhes" user "B.Adhesive")
		(13 "F.Paste" user "Package Geometry/Pastemask Top")
		(15 "B.Paste" user "Package Geometry/Pastemask Bottom")
		(5 "F.SilkS" user "Ref Des/Silkscreen Top")
		(7 "B.SilkS" user "Ref Des/Silkscreen Bottom")
		(1 "F.Mask" user "Board Geometry/Soldermask Top")
		(3 "B.Mask" user "Board Geometry/Soldermask Bottom")
		(17 "Dwgs.User" user "User.Drawings")
		(19 "Cmts.User" user "User.Comments")
		(21 "Eco1.User" user "User.Eco1")
		(23 "Eco2.User" user "User.Eco2")
		(25 "Edge.Cuts" user "Board Geometry/Outline")
		(27 "Margin" user)
		(31 "F.CrtYd" user "Package Geometry/Place Bound Top")
		(29 "B.CrtYd" user "Package Geometry/Place Bound Bottom")
		(35 "F.Fab" user "Ref Des/Assembly Top")
		(33 "B.Fab" user "Ref Des/Assembly Bottom")
	)
	(footprint ""
		(layer "F.Cu")
		(at 260.340094 -141.968728 90)
		(property "Reference" "R605"
			(at 0 0 90)
			(layer "F.SilkS")
			(hide yes)
			(effects
				(font
					(size 1.27 1.27)
				)
			)
		)
		(property "Value" ""
			(at 0 0 90)
			(layer "F.Fab")
			(effects
				(font
					(size 1.27 1.27)
				)
			)
		)
		(duplicate_pad_numbers_are_jumpers no)
		(fp_line
			(start 0.7874 -0.4064)
			(end 0.7874 0.4064)
			(stroke
				(width 0.1524)
				(type default)
			)
			(layer "F.SilkS")
		)
		(fp_line
			(start -0.7874 -0.4064)
			(end 0.7874 -0.4064)
			(stroke
				(width 0.1524)
				(type default)
			)
			(layer "F.SilkS")
		)
		(fp_line
			(start 0.7874 0.4064)
			(end -0.7874 0.4064)
			(stroke
				(width 0.1524)
				(type default)
			)
			(layer "F.SilkS")
		)
		(fp_line
			(start -0.7874 0.4064)
			(end -0.7874 -0.4064)
			(stroke
				(width 0.1524)
				(type default)
			)
			(layer "F.SilkS")
		)
		(fp_line
			(start -0.12065 -0.305054)
			(end -0.12065 -0.2794)
			(stroke
				(width 0.1)
				(type default)
			)
			(layer "F.Fab")
		)
		(fp_line
			(start -0.67945 -0.305054)
			(end -0.12065 -0.305054)
			(stroke
				(width 0.1)
				(type default)
			)
			(layer "F.Fab")
		)
		(fp_line
			(start 0.67945 -0.3048)
			(end 0.67945 0.3048)
			(stroke
				(width 0.1)
				(type default)
			)
			(layer "F.Fab")
		)
		(fp_line
			(start 0.12065 -0.3048)
			(end 0.67945 -0.3048)
			(stroke
				(width 0.1)
				(type default)
			)
			(layer "F.Fab")
		)
		(fp_line
			(start 0.12065 -0.2794)
			(end 0.12065 -0.3048)
			(stroke
				(width 0.1)
				(type default)
			)
			(layer "F.Fab")
		)
		(fp_line
			(start -0.12065 -0.2794)
			(end 0.12065 -0.2794)
			(stroke
				(width 0.1)
				(type default)
			)
			(layer "F.Fab")
		)
		(fp_line
			(start 0.120396 0.2794)
			(end -0.12065 0.2794)
			(stroke
				(width 0.1)
				(type default)
			)
			(layer "F.Fab")
		)
		(fp_line
			(start -0.12065 0.2794)
			(end -0.12065 0.3048)
			(stroke
				(width 0.1)
				(type default)
			)
			(layer "F.Fab")
		)
		(fp_line
			(start 0.67945 0.3048)
			(end 0.120396 0.3048)
			(stroke
				(width 0.1)
				(type default)
			)
			(layer "F.Fab")
		)
		(fp_line
			(start 0.120396 0.3048)
			(end 0.120396 0.2794)
			(stroke
				(width 0.1)
				(type default)
			)
			(layer "F.Fab")
		)
		(fp_line
			(start -0.12065 0.3048)
			(end -0.67945 0.3048)
			(stroke
				(width 0.1)
				(type default)
			)
			(layer "F.Fab")
		)
		(fp_line
			(start -0.67945 0.3048)
			(end -0.67945 -0.305054)
			(stroke
				(width 0.1)
				(type default)
			)
			(layer "F.Fab")
		)
		(pad "1" smd circle
			(at -0.40005 0 90)
			(size 0 0)
			(layers "F.Cu" "F.Mask" "F.Paste")
			(net "SPI_CPU0_LVC3_D1")
		)
		(pad "2" smd circle
			(at 0.40005 0 90)
			(size 0 0)
			(layers "F.Cu" "F.Mask" "F.Paste")
			(net "SPI_CPU0_LVC3_SCM_D1")
		)
	)
	(footprint ""
		(layer "F.Cu")
		(at 336.172556 -131.99745)
		(property "Reference" "PC8002"
			(at 0 0 0)
			(layer "F.SilkS")
			(hide yes)
			(effects
				(font
					(size 1.27 1.27)
				)
			)
		)
		(property "Value" ""
			(at 0 0 0)
			(layer "F.Fab")
			(effects
				(font
					(size 1.27 1.27)
				)
			)
		)
		(duplicate_pad_numbers_are_jumpers no)
		(fp_line
			(start -1.524 -0.762)
			(end 1.524 -0.762)
			(stroke
				(width 0.1524)
				(type default)
			)
			(layer "F.SilkS")
		)
		(fp_line
			(start -1.524 0.762)
			(end -1.524 -0.762)
			(stroke
				(width 0.1524)
				(type default)
			)
			(layer "F.SilkS")
		)
		(fp_line
			(start 1.524 -0.762)
			(end 1.524 0.762)
			(stroke
				(width 0.1524)
				(type default)
			)
			(layer "F.SilkS")
		)
		(fp_line
			(start 1.524 0.762)
			(end -1.524 0.762)
			(stroke
				(width 0.1524)
				(type default)
			)
			(layer "F.SilkS")
		)
		(fp_line
			(start -1.1049 -0.724916)
			(end -1.1049 0.724916)
			(stroke
				(width 0.1)
				(type default)
			)
			(layer "F.Fab")
		)
		(fp_line
			(start -1.1049 0.724916)
			(end 1.1049 0.724916)
			(stroke
				(width 0.1)
				(type default)
			)
			(layer "F.Fab")
		)
		(fp_line
			(start 1.1049 -0.724916)
			(end -1.1049 -0.724916)
			(stroke
				(width 0.1)
				(type default)
			)
			(layer "F.Fab")
		)
		(fp_line
			(start 1.1049 0.724916)
			(end 1.1049 -0.724916)
			(stroke
				(width 0.1)
				(type default)
			)
			(layer "F.Fab")
		)
		(pad "1" smd rect
			(at -0.889 0 180)
			(size 1.016 1.27)
			(layers "F.Cu" "F.Mask" "F.Paste")
			(net "SW_P12V_AUX_PVDD18_S5_P0_FLT")
		)
		(pad "2" smd rect
			(at 0.889 0 180)
			(size 1.016 1.27)
			(layers "F.Cu" "F.Mask" "F.Paste")
			(net "GND")
		)
	)
	(footprint ""
		(layer "F.Cu")
		(at 5.260086 -35.495484 180)
		(property "Reference" ""
			(at 0 0 180)
			(layer "F.SilkS")
			(hide yes)
			(effects
				(font
					(size 1.27 1.27)
				)
			)
		)
		(property "Value" ""
			(at 0 0 180)
			(layer "F.Fab")
			(effects
				(font
					(size 1.27 1.27)
				)
			)
		)
		(duplicate_pad_numbers_are_jumpers no)
		(pad "1" smd circle
			(at 0 0 180)
			(size 0.9906 0.9906)
			(layers "F.Cu" "F.Mask" "F.Paste")
			(net "Net_10726")
		)
		(zone
			(layer "F.Cu")
			(hatch none 0.5)
			(connect_pads
				(clearance 0)
			)
			(min_thickness 0.25)
			(keepout
				(tracks not_allowed)
				(vias allowed)
				(pads allowed)
				(copperpour not_allowed)
				(footprints allowed)
			)
			(placement
				(enabled no)
				(sheetname "")
			)
			(fill
				(thermal_gap 0.5)
				(thermal_bridge_width 0.5)
				(island_removal_mode 0)
			)
			(polygon
				(pts
					(arc
						(start 6.885686 -35.495484)
						(mid 3.634486 -35.495484)
						(end 6.885686 -35.495484)
					)
				)
			)
		)
	)
	(footprint ""
		(layer "F.Cu")
		(at 10.066782 -408.405584 180)
		(property "Reference" "PC819"
			(at 0 0 180)
			(layer "F.SilkS")
			(hide yes)
			(effects
				(font
					(size 1.27 1.27)
				)
			)
		)
		(property "Value" ""
			(at 0 0 180)
			(layer "F.Fab")
			(effects
				(font
					(size 1.27 1.27)
				)
			)
		)
		(duplicate_pad_numbers_are_jumpers no)
		(fp_line
			(start 0.7874 0.4064)
			(end -0.7874 0.4064)
			(stroke
				(width 0.1524)
				(type default)
			)
			(layer "F.SilkS")
		)
		(fp_line
			(start 0.7874 -0.4064)
			(end 0.7874 0.4064)
			(stroke
				(width 0.1524)
				(type default)
			)
			(layer "F.SilkS")
		)
		(fp_line
			(start -0.7874 0.4064)
			(end -0.7874 -0.4064)
			(stroke
				(width 0.1524)
				(type default)
			)
			(layer "F.SilkS")
		)
		(fp_line
			(start -0.7874 -0.4064)
			(end 0.7874 -0.4064)
			(stroke
				(width 0.1524)
				(type default)
			)
			(layer "F.SilkS")
		)
		(fp_line
			(start 0.67945 0.3048)
			(end 0.120396 0.3048)
			(stroke
				(width 0.1)
				(type default)
			)
			(layer "F.Fab")
		)
		(fp_line
			(start 0.67945 -0.3048)
			(end 0.67945 0.3048)
			(stroke
				(width 0.1)
				(type default)
			)
			(layer "F.Fab")
		)
		(fp_line
			(start 0.12065 -0.2794)
			(end 0.12065 -0.3048)
			(stroke
				(width 0.1)
				(type default)
			)
			(layer "F.Fab")
		)
		(fp_line
			(start 0.12065 -0.3048)
			(end 0.67945 -0.3048)
			(stroke
				(width 0.1)
				(type default)
			)
			(layer "F.Fab")
		)
		(fp_line
			(start 0.120396 0.3048)
			(end 0.120396 0.2794)
			(stroke
				(width 0.1)
				(type default)
			)
			(layer "F.Fab")
		)
		(fp_line
			(start 0.120396 0.2794)
			(end -0.12065 0.2794)
			(stroke
				(width 0.1)
				(type default)
			)
			(layer "F.Fab")
		)
		(fp_line
			(start -0.12065 0.3048)
			(end -0.67945 0.3048)
			(stroke
				(width 0.1)
				(type default)
			)
			(layer "F.Fab")
		)
		(fp_line
			(start -0.12065 0.2794)
			(end -0.12065 0.3048)
			(stroke
				(width 0.1)
				(type default)
			)
			(layer "F.Fab")
		)
		(fp_line
			(start -0.12065 -0.2794)
			(end 0.12065 -0.2794)
			(stroke
				(width 0.1)
				(type default)
			)
			(layer "F.Fab")
		)
		(fp_line
			(start -0.12065 -0.305054)
			(end -0.12065 -0.2794)
			(stroke
				(width 0.1)
				(type default)
			)
			(layer "F.Fab")
		)
		(fp_line
			(start -0.67945 0.3048)
			(end -0.67945 -0.305054)
			(stroke
				(width 0.1)
				(type default)
			)
			(layer "F.Fab")
		)
		(fp_line
			(start -0.67945 -0.305054)
			(end -0.12065 -0.305054)
			(stroke
				(width 0.1)
				(type default)
			)
			(layer "F.Fab")
		)
		(pad "1" smd circle
			(at -0.40005 0 180)
			(size 0 0)
			(layers "F.Cu" "F.Mask" "F.Paste")
			(net "P0V9_RETIMER_CPU1_VINSEN")
		)
		(pad "2" smd circle
			(at 0.40005 0 180)
			(size 0 0)
			(layers "F.Cu" "F.Mask" "F.Paste")
			(net "GND")
		)
	)
	(footprint ""
		(layer "F.Cu")
		(at 57.518554 -373.03583 -90)
		(property "Reference" "C820"
			(at 0 0 270)
			(layer "F.SilkS")
			(hide yes)
			(effects
				(font
					(size 1.27 1.27)
				)
			)
		)
		(property "Value" ""
			(at 0 0 270)
			(layer "F.Fab")
			(effects
				(font
					(size 1.27 1.27)
				)
			)
		)
		(duplicate_pad_numbers_are_jumpers no)
		(fp_line
			(start -0.299974 0.150114)
			(end -0.299974 -0.150114)
			(stroke
				(width 0.1)
				(type default)
			)
			(layer "F.Fab")
		)
		(fp_line
			(start 0.299974 0.150114)
			(end -0.299974 0.150114)
			(stroke
				(width 0.1)
				(type default)
			)
			(layer "F.Fab")
		)
		(fp_line
			(start -0.299974 -0.150114)
			(end 0.299974 -0.150114)
			(stroke
				(width 0.1)
				(type default)
			)
			(layer "F.Fab")
		)
		(fp_line
			(start 0.299974 -0.150114)
			(end 0.299974 0.150114)
			(stroke
				(width 0.1)
				(type default)
			)
			(layer "F.Fab")
		)
		(pad "1" smd rect
			(at -0.2667 0 270)
			(size 0.3048 0.381)
			(layers "F.Cu" "F.Mask" "F.Paste")
			(net "P5E_CPU1_P0_TX_C_DN<8>")
		)
		(pad "2" smd rect
			(at 0.2667 0 270)
			(size 0.3048 0.381)
			(layers "F.Cu" "F.Mask" "F.Paste")
			(net "P5E_CPU1_P0_TX_DN<8>")
		)
	)
	(footprint ""
		(layer "F.Cu")
		(at 42.49293 -351.578672 90)
		(property "Reference" "PC436_8"
			(at 0 0 90)
			(layer "F.SilkS")
			(hide yes)
			(effects
				(font
					(size 1.27 1.27)
				)
			)
		)
		(property "Value" ""
			(at 0 0 90)
			(layer "F.Fab")
			(effects
				(font
					(size 1.27 1.27)
				)
			)
		)
		(duplicate_pad_numbers_are_jumpers no)
		(fp_line
			(start 0.7874 -0.4064)
			(end 0.7874 0.4064)
			(stroke
				(width 0.1524)
				(type default)
			)
			(layer "F.SilkS")
		)
		(fp_line
			(start -0.7874 -0.4064)
			(end 0.7874 -0.4064)
			(stroke
				(width 0.1524)
				(type default)
			)
			(layer "F.SilkS")
		)
		(fp_line
			(start 0.7874 0.4064)
			(end -0.7874 0.4064)
			(stroke
				(width 0.1524)
				(type default)
			)
			(layer "F.SilkS")
		)
		(fp_line
			(start -0.7874 0.4064)
			(end -0.7874 -0.4064)
			(stroke
				(width 0.1524)
				(type default)
			)
			(layer "F.SilkS")
		)
		(fp_line
			(start -0.12065 -0.305054)
			(end -0.12065 -0.2794)
			(stroke
				(width 0.1)
				(type default)
			)
			(layer "F.Fab")
		)
		(fp_line
			(start -0.67945 -0.305054)
			(end -0.12065 -0.305054)
			(stroke
				(width 0.1)
				(type default)
			)
			(layer "F.Fab")
		)
		(fp_line
			(start 0.67945 -0.3048)
			(end 0.67945 0.3048)
			(stroke
				(width 0.1)
				(type default)
			)
			(layer "F.Fab")
		)
		(fp_line
			(start 0.12065 -0.3048)
			(end 0.67945 -0.3048)
			(stroke
				(width 0.1)
				(type default)
			)
			(layer "F.Fab")
		)
		(fp_line
			(start 0.12065 -0.2794)
			(end 0.12065 -0.3048)
			(stroke
				(width 0.1)
				(type default)
			)
			(layer "F.Fab")
		)
		(fp_line
			(start -0.12065 -0.2794)
			(end 0.12065 -0.2794)
			(stroke
				(width 0.1)
				(type default)
			)
			(layer "F.Fab")
		)
		(fp_line
			(start 0.120396 0.2794)
			(end -0.12065 0.2794)
			(stroke
				(width 0.1)
				(type default)
			)
			(layer "F.Fab")
		)
		(fp_line
			(start -0.12065 0.2794)
			(end -0.12065 0.3048)
			(stroke
				(width 0.1)
				(type default)
			)
			(layer "F.Fab")
		)
		(fp_line
			(start 0.67945 0.3048)
			(end 0.120396 0.3048)
			(stroke
				(width 0.1)
				(type default)
			)
			(layer "F.Fab")
		)
		(fp_line
			(start 0.120396 0.3048)
			(end 0.120396 0.2794)
			(stroke
				(width 0.1)
				(type default)
			)
			(layer "F.Fab")
		)
		(fp_line
			(start -0.12065 0.3048)
			(end -0.67945 0.3048)
			(stroke
				(width 0.1)
				(type default)
			)
			(layer "F.Fab")
		)
		(fp_line
			(start -0.67945 0.3048)
			(end -0.67945 -0.305054)
			(stroke
				(width 0.1)
				(type default)
			)
			(layer "F.Fab")
		)
		(pad "1" smd circle
			(at -0.40005 0 90)
			(size 0 0)
			(layers "F.Cu" "F.Mask" "F.Paste")
			(net "PVDDCR_CPU1_P1_VCCS")
		)
		(pad "2" smd circle
			(at 0.40005 0 90)
			(size 0 0)
			(layers "F.Cu" "F.Mask" "F.Paste")
			(net "GND")
		)
	)
	(footprint ""
		(layer "F.Cu")
		(at 22.479 -361.061 180)
		(property "Reference" "C309"
			(at 0 0 180)
			(layer "F.SilkS")
			(hide yes)
			(effects
				(font
					(size 1.27 1.27)
				)
			)
		)
		(property "Value" ""
			(at 0 0 180)
			(layer "F.Fab")
			(effects
				(font
					(size 1.27 1.27)
				)
			)
		)
		(duplicate_pad_numbers_are_jumpers no)
		(fp_line
			(start 0.7874 0.4064)
			(end -0.7874 0.4064)
			(stroke
				(width 0.1524)
				(type default)
			)
			(layer "F.SilkS")
		)
		(fp_line
			(start 0.7874 -0.4064)
			(end 0.7874 0.4064)
			(stroke
				(width 0.1524)
				(type default)
			)
			(layer "F.SilkS")
		)
		(fp_line
			(start -0.7874 0.4064)
			(end -0.7874 -0.4064)
			(stroke
				(width 0.1524)
				(type default)
			)
			(layer "F.SilkS")
		)
		(fp_line
			(start -0.7874 -0.4064)
			(end 0.7874 -0.4064)
			(stroke
				(width 0.1524)
				(type default)
			)
			(layer "F.SilkS")
		)
		(fp_line
			(start 0.67945 0.3048)
			(end 0.120396 0.3048)
			(stroke
				(width 0.1)
				(type default)
			)
			(layer "F.Fab")
		)
		(fp_line
			(start 0.67945 -0.3048)
			(end 0.67945 0.3048)
			(stroke
				(width 0.1)
				(type default)
			)
			(layer "F.Fab")
		)
		(fp_line
			(start 0.12065 -0.2794)
			(end 0.12065 -0.3048)
			(stroke
				(width 0.1)
				(type default)
			)
			(layer "F.Fab")
		)
		(fp_line
			(start 0.12065 -0.3048)
			(end 0.67945 -0.3048)
			(stroke
				(width 0.1)
				(type default)
			)
			(layer "F.Fab")
		)
		(fp_line
			(start 0.120396 0.3048)
			(end 0.120396 0.2794)
			(stroke
				(width 0.1)
				(type default)
			)
			(layer "F.Fab")
		)
		(fp_line
			(start 0.120396 0.2794)
			(end -0.12065 0.2794)
			(stroke
				(width 0.1)
				(type default)
			)
			(layer "F.Fab")
		)
		(fp_line
			(start -0.12065 0.3048)
			(end -0.67945 0.3048)
			(stroke
				(width 0.1)
				(type default)
			)
			(layer "F.Fab")
		)
		(fp_line
			(start -0.12065 0.2794)
			(end -0.12065 0.3048)
			(stroke
				(width 0.1)
				(type default)
			)
			(layer "F.Fab")
		)
		(fp_line
			(start -0.12065 -0.2794)
			(end 0.12065 -0.2794)
			(stroke
				(width 0.1)
				(type default)
			)
			(layer "F.Fab")
		)
		(fp_line
			(start -0.12065 -0.305054)
			(end -0.12065 -0.2794)
			(stroke
				(width 0.1)
				(type default)
			)
			(layer "F.Fab")
		)
		(fp_line
			(start -0.67945 0.3048)
			(end -0.67945 -0.305054)
			(stroke
				(width 0.1)
				(type default)
			)
			(layer "F.Fab")
		)
		(fp_line
			(start -0.67945 -0.305054)
			(end -0.12065 -0.305054)
			(stroke
				(width 0.1)
				(type default)
			)
			(layer "F.Fab")
		)
		(pad "1" smd circle
			(at -0.40005 0 180)
			(size 0 0)
			(layers "F.Cu" "F.Mask" "F.Paste")
			(net "SVID_PVDDCR_CPU1_P1_SVD_R")
		)
		(pad "2" smd circle
			(at 0.40005 0 180)
			(size 0 0)
			(layers "F.Cu" "F.Mask" "F.Paste")
			(net "GND")
		)
	)
	(footprint ""
		(layer "F.Cu")
		(at 169.418 -134.493)
		(property "Reference" "R480"
			(at 0 0 0)
			(layer "F.SilkS")
			(hide yes)
			(effects
				(font
					(size 1.27 1.27)
				)
			)
		)
		(property "Value" ""
			(at 0 0 0)
			(layer "F.Fab")
			(effects
				(font
					(size 1.27 1.27)
				)
			)
		)
		(duplicate_pad_numbers_are_jumpers no)
		(fp_line
			(start -0.7874 -0.4064)
			(end 0.7874 -0.4064)
			(stroke
				(width 0.1524)
				(type default)
			)
			(layer "F.SilkS")
		)
		(fp_line
			(start -0.7874 0.4064)
			(end -0.7874 -0.4064)
			(stroke
				(width 0.1524)
				(type default)
			)
			(layer "F.SilkS")
		)
		(fp_line
			(start 0.7874 -0.4064)
			(end 0.7874 0.4064)
			(stroke
				(width 0.1524)
				(type default)
			)
			(layer "F.SilkS")
		)
		(fp_line
			(start 0.7874 0.4064)
			(end -0.7874 0.4064)
			(stroke
				(width 0.1524)
				(type default)
			)
			(layer "F.SilkS")
		)
		(fp_line
			(start -0.67945 -0.305054)
			(end -0.12065 -0.305054)
			(stroke
				(width 0.1)
				(type default)
			)
			(layer "F.Fab")
		)
		(fp_line
			(start -0.67945 0.3048)
			(end -0.67945 -0.305054)
			(stroke
				(width 0.1)
				(type default)
			)
			(layer "F.Fab")
		)
		(fp_line
			(start -0.12065 -0.305054)
			(end -0.12065 -0.2794)
			(stroke
				(width 0.1)
				(type default)
			)
			(layer "F.Fab")
		)
		(fp_line
			(start -0.12065 -0.2794)
			(end 0.12065 -0.2794)
			(stroke
				(width 0.1)
				(type default)
			)
			(layer "F.Fab")
		)
		(fp_line
			(start -0.12065 0.2794)
			(end -0.12065 0.3048)
			(stroke
				(width 0.1)
				(type default)
			)
			(layer "F.Fab")
		)
		(fp_line
			(start -0.12065 0.3048)
			(end -0.67945 0.3048)
			(stroke
				(width 0.1)
				(type default)
			)
			(layer "F.Fab")
		)
		(fp_line
			(start 0.120396 0.2794)
			(end -0.12065 0.2794)
			(stroke
				(width 0.1)
				(type default)
			)
			(layer "F.Fab")
		)
		(fp_line
			(start 0.120396 0.3048)
			(end 0.120396 0.2794)
			(stroke
				(width 0.1)
				(type default)
			)
			(layer "F.Fab")
		)
		(fp_line
			(start 0.12065 -0.3048)
			(end 0.67945 -0.3048)
			(stroke
				(width 0.1)
				(type default)
			)
			(layer "F.Fab")
		)
		(fp_line
			(start 0.12065 -0.2794)
			(end 0.12065 -0.3048)
			(stroke
				(width 0.1)
				(type default)
			)
			(layer "F.Fab")
		)
		(fp_line
			(start 0.67945 -0.3048)
			(end 0.67945 0.3048)
			(stroke
				(width 0.1)
				(type default)
			)
			(layer "F.Fab")
		)
		(fp_line
			(start 0.67945 0.3048)
			(end 0.120396 0.3048)
			(stroke
				(width 0.1)
				(type default)
			)
			(layer "F.Fab")
		)
		(pad "1" smd circle
			(at -0.40005 0)
			(size 0 0)
			(layers "F.Cu" "F.Mask" "F.Paste")
			(net "PWRGD_P5V_R")
		)
		(pad "2" smd circle
			(at 0.40005 0)
			(size 0 0)
			(layers "F.Cu" "F.Mask" "F.Paste")
			(net "GND")
		)
	)
)
